# S9S_MB_2U (Grand Teton) — schematic netlist excerpt (pin names and nets, part order shuffled) for the footprints in the layout excerpt that follows; sources: Cadence DE-HDL packaged netlist, KiCad conversion of 03242023_DA0F0TMBIJ0_F0T_Motherboard_J_brd_V01_OCP.brd

Q52  MOSFET_NCH_GDS_ESD_PROTECTED  2N7002K IC  pkg SOT23_GDSXC  page 244
  D  = FM_COMP_P3V3_AUX_VIN_R
  G  = PWRGD_P3V3_AUX_R2
  S  = GND

PR3984  Q_RES  120K 1% CHIP  pkg 0402LF  page 303 : A = AGND_HSC ; B = HSC_MODE_4

(kicad_pcb
	(version 20260206)
	(generator "pcbnew")
	(generator_version "10.0")
	(general
		(thickness 1.6)
		(legacy_teardrops no)
	)
	(paper "A4")
	(title_block
		(title "03242023_DA0F0TMBIJ0_F0T_Motherboard_J_brd_V01_OCP.brd")
		(comment 1 "Grand Teton / footprints 2362-2363 of 6105")
	)
	(layers
		(0 "F.Cu" signal "TOP")
		(4 "In1.Cu" signal "GND")
		(6 "In2.Cu" signal "IN1")
		(8 "In3.Cu" signal "GND1")
		(10 "In4.Cu" signal "IN2")
		(12 "In5.Cu" signal "GND2")
		(14 "In6.Cu" signal "IN3")
		(16 "In7.Cu" signal "GND3")
		(18 "In8.Cu" signal "VCC")
		(20 "In9.Cu" signal "VCC1")
		(22 "In10.Cu" signal "GND4")
		(24 "In11.Cu" signal "IN4")
		(26 "In12.Cu" signal "GND5")
		(28 "In13.Cu" signal "IN5")
		(30 "In14.Cu" signal "GND6")
		(32 "In15.Cu" signal "IN6")
		(34 "In16.Cu" signal "GND7")
		(2 "B.Cu" signal "BOTTOM")
		(9 "F.Adhes" user "F.Adhesive")
		(11 "B.Adhes" user "B.Adhesive")
		(13 "F.Paste" user "Package Geometry/Pastemask Top")
		(15 "B.Paste" user "Package Geometry/Pastemask Bottom")
		(5 "F.SilkS" user "Ref Des/Silkscreen Top")
		(7 "B.SilkS" user "Ref Des/Silkscreen Bottom")
		(1 "F.Mask" user "Board Geometry/Soldermask Top")
		(3 "B.Mask" user "Board Geometry/Soldermask Bottom")
		(17 "Dwgs.User" user "User.Drawings")
		(19 "Cmts.User" user "User.Comments")
		(21 "Eco1.User" user "User.Eco1")
		(23 "Eco2.User" user "User.Eco2")
		(25 "Edge.Cuts" user "Board Geometry/Outline")
		(27 "Margin" user)
		(31 "F.CrtYd" user "Package Geometry/Place Bound Top")
		(29 "B.CrtYd" user "Package Geometry/Place Bound Bottom")
		(35 "F.Fab" user "Ref Des/Assembly Top")
		(33 "B.Fab" user "Ref Des/Assembly Bottom")
	)
	(footprint ""
		(layer "F.Cu")
		(at 237.401608 -404.721822 180)
		(property "Reference" "PR3984"
			(at 0 0 180)
			(layer "F.SilkS")
			(hide yes)
			(effects
				(font
					(size 1.27 1.27)
				)
			)
		)
		(property "Value" ""
			(at 0 0 180)
			(layer "F.Fab")
			(effects
				(font
					(size 1.27 1.27)
				)
			)
		)
		(duplicate_pad_numbers_are_jumpers no)
		(fp_line
			(start 0.7874 0.4064)
			(end -0.7874 0.4064)
			(stroke
				(width 0.1524)
				(type default)
			)
			(layer "F.SilkS")
		)
		(fp_line
			(start 0.7874 -0.4064)
			(end 0.7874 0.4064)
			(stroke
				(width 0.1524)
				(type default)
			)
			(layer "F.SilkS")
		)
		(fp_line
			(start -0.7874 0.4064)
			(end -0.7874 -0.4064)
			(stroke
				(width 0.1524)
				(type default)
			)
			(layer "F.SilkS")
		)
		(fp_line
			(start -0.7874 -0.4064)
			(end 0.7874 -0.4064)
			(stroke
				(width 0.1524)
				(type default)
			)
			(layer "F.SilkS")
		)
		(fp_line
			(start 0.67945 0.3048)
			(end 0.120396 0.3048)
			(stroke
				(width 0.1)
				(type default)
			)
			(layer "F.Fab")
		)
		(fp_line
			(start 0.67945 -0.3048)
			(end 0.67945 0.3048)
			(stroke
				(width 0.1)
				(type default)
			)
			(layer "F.Fab")
		)
		(fp_line
			(start 0.12065 -0.2794)
			(end 0.12065 -0.3048)
			(stroke
				(width 0.1)
				(type default)
			)
			(layer "F.Fab")
		)
		(fp_line
			(start 0.12065 -0.3048)
			(end 0.67945 -0.3048)
			(stroke
				(width 0.1)
				(type default)
			)
			(layer "F.Fab")
		)
		(fp_line
			(start 0.120396 0.3048)
			(end 0.120396 0.2794)
			(stroke
				(width 0.1)
				(type default)
			)
			(layer "F.Fab")
		)
		(fp_line
			(start 0.120396 0.2794)
			(end -0.12065 0.2794)
			(stroke
				(width 0.1)
				(type default)
			)
			(layer "F.Fab")
		)
		(fp_line
			(start -0.12065 0.3048)
			(end -0.67945 0.3048)
			(stroke
				(width 0.1)
				(type default)
			)
			(layer "F.Fab")
		)
		(fp_line
			(start -0.12065 0.2794)
			(end -0.12065 0.3048)
			(stroke
				(width 0.1)
				(type default)
			)
			(layer "F.Fab")
		)
		(fp_line
			(start -0.12065 -0.2794)
			(end 0.12065 -0.2794)
			(stroke
				(width 0.1)
				(type default)
			)
			(layer "F.Fab")
		)
		(fp_line
			(start -0.12065 -0.305054)
			(end -0.12065 -0.2794)
			(stroke
				(width 0.1)
				(type default)
			)
			(layer "F.Fab")
		)
		(fp_line
			(start -0.67945 0.3048)
			(end -0.67945 -0.305054)
			(stroke
				(width 0.1)
				(type default)
			)
			(layer "F.Fab")
		)
		(fp_line
			(start -0.67945 -0.305054)
			(end -0.12065 -0.305054)
			(stroke
				(width 0.1)
				(type default)
			)
			(layer "F.Fab")
		)
		(pad "1" smd circle
			(at -0.40005 0 180)
			(size 0 0)
			(layers "F.Cu" "F.Mask" "F.Paste")
			(net "AGND_HSC")
		)
		(pad "2" smd circle
			(at 0.40005 0 180)
			(size 0 0)
			(layers "F.Cu" "F.Mask" "F.Paste")
			(net "HSC_MODE_4")
		)
	)
	(footprint ""
		(layer "F.Cu")
		(at 157.28188 -131.155948 -90)
		(property "Reference" "Q52"
			(at -2.55905 0.86614 0)
			(unlocked yes)
			(layer "F.SilkS")
			(effects
				(font
					(size 0.7874 0.5842)
					(thickness 0.1524)
				)
				(justify left)
			)
		)
		(property "Value" ""
			(at 0 0 270)
			(layer "F.Fab")
			(effects
				(font
					(size 1.27 1.27)
				)
			)
		)
		(duplicate_pad_numbers_are_jumpers no)
		(fp_line
			(start -1.603248 1.500124)
			(end -1.603248 -1.500124)
			(stroke
				(width 0.1524)
				(type default)
			)
			(layer "F.SilkS")
		)
		(fp_line
			(start 1.603248 1.500124)
			(end -1.603248 1.500124)
			(stroke
				(width 0.1524)
				(type default)
			)
			(layer "F.SilkS")
		)
		(fp_line
			(start -1.603248 -1.500124)
			(end 1.603248 -1.500124)
			(stroke
				(width 0.1524)
				(type default)
			)
			(layer "F.SilkS")
		)
		(fp_line
			(start 1.603248 -1.500124)
			(end 1.603248 1.500124)
			(stroke
				(width 0.1524)
				(type default)
			)
			(layer "F.SilkS")
		)
		(fp_line
			(start -0.700024 1.500124)
			(end 0.700024 1.500124)
			(stroke
				(width 0.1)
				(type default)
			)
			(layer "F.Fab")
		)
		(fp_line
			(start 0.700024 1.500124)
			(end 0.700024 0.219964)
			(stroke
				(width 0.1)
				(type default)
			)
			(layer "F.Fab")
		)
		(fp_line
			(start -1.249934 1.169924)
			(end -0.700024 1.169924)
			(stroke
				(width 0.1)
				(type default)
			)
			(layer "F.Fab")
		)
		(fp_line
			(start -0.700024 1.169924)
			(end -0.700024 1.500124)
			(stroke
				(width 0.1)
				(type default)
			)
			(layer "F.Fab")
		)
		(fp_line
			(start -1.249934 0.729996)
			(end -1.249934 1.169924)
			(stroke
				(width 0.1)
				(type default)
			)
			(layer "F.Fab")
		)
		(fp_line
			(start -0.6985 0.729996)
			(end -1.249934 0.729996)
			(stroke
				(width 0.1)
				(type default)
			)
			(layer "F.Fab")
		)
		(fp_line
			(start 0.700024 0.219964)
			(end 1.249934 0.219964)
			(stroke
				(width 0.1)
				(type default)
			)
			(layer "F.Fab")
		)
		(fp_line
			(start 1.249934 0.219964)
			(end 1.249934 -0.219964)
			(stroke
				(width 0.1)
				(type default)
			)
			(layer "F.Fab")
		)
		(fp_line
			(start 0.700024 -0.219964)
			(end 0.700024 -1.500124)
			(stroke
				(width 0.1)
				(type default)
			)
			(layer "F.Fab")
		)
		(fp_line
			(start 1.249934 -0.219964)
			(end 0.700024 -0.219964)
			(stroke
				(width 0.1)
				(type default)
			)
			(layer "F.Fab")
		)
		(fp_line
			(start -1.249934 -0.729996)
			(end -0.6985 -0.729996)
			(stroke
				(width 0.1)
				(type default)
			)
			(layer "F.Fab")
		)
		(fp_line
			(start -0.6985 -0.729996)
			(end -0.6985 0.729996)
			(stroke
				(width 0.1)
				(type default)
			)
			(layer "F.Fab")
		)
		(fp_line
			(start -1.249934 -1.169924)
			(end -1.249934 -0.729996)
			(stroke
				(width 0.1)
				(type default)
			)
			(layer "F.Fab")
		)
		(fp_line
			(start -0.700024 -1.169924)
			(end -1.249934 -1.169924)
			(stroke
				(width 0.1)
				(type default)
			)
			(layer "F.Fab")
		)
		(fp_line
			(start -0.700024 -1.500124)
			(end -0.700024 -1.169924)
			(stroke
				(width 0.1)
				(type default)
			)
			(layer "F.Fab")
		)
		(fp_line
			(start 0.700024 -1.500124)
			(end -0.700024 -1.500124)
			(stroke
				(width 0.1)
				(type default)
			)
			(layer "F.Fab")
		)
		(fp_rect
			(start -0.700024 1.500124)
			(end 0.700024 -1.500124)
			(stroke
				(width 0)
				(type default)
			)
			(fill no)
			(layer "F.Fab")
		)
		(pad "D" smd rect
			(at 0.999998 0 180)
			(size 0.8128 0.9144)
			(layers "F.Cu" "F.Mask" "F.Paste")
			(net "FM_COMP_P3V3_AUX_VIN_R")
		)
		(pad "G" smd rect
			(at -0.999998 -0.94996 180)
			(size 0.8128 0.9144)
			(layers "F.Cu" "F.Mask" "F.Paste")
			(net "PWRGD_P3V3_AUX_R2")
		)
		(pad "S" smd rect
			(at -0.999998 0.94996 180)
			(size 0.8128 0.9144)
			(layers "F.Cu" "F.Mask" "F.Paste")
			(net "GND")
		)
	)
)
